# S9S_MB_2U (Grand Teton) — schematic netlist excerpt (pin names and nets, part order shuffled) for the footprints in the layout excerpt that follows; sources: Cadence DE-HDL packaged netlist, KiCad conversion of 03242023_DA0F0TMBIJ0_F0T_Motherboard_J_brd_V01_OCP.brd

R416  Q_RES  0 5% CHIP  pkg 0402LF  page 153 : A = OCP_SFF_ISO_BIF0_EN ; B = OCP_SFF_BIF0_R_N
H26  HOLE  EMPTY  pkg TH  page 311 : \1\ = NC
C1102  Q_CAP_DIFFBUS  DIFF BUS_0.22UF 6.3V 20% X6S  pkg C0201  page 181 : \1\ = P3E_PCH_M2_TX_DP<1> ; \2\ = P3E_PCH_M2_TX_C_DP<1>

(kicad_pcb
	(version 20260206)
	(generator "pcbnew")
	(generator_version "10.0")
	(general
		(thickness 1.6)
		(legacy_teardrops no)
	)
	(paper "A4")
	(title_block
		(title "03242023_DA0F0TMBIJ0_F0T_Motherboard_J_brd_V01_OCP.brd")
		(comment 1 "Grand Teton / footprints 8-10 of 6105")
	)
	(layers
		(0 "F.Cu" signal "TOP")
		(4 "In1.Cu" signal "GND")
		(6 "In2.Cu" signal "IN1")
		(8 "In3.Cu" signal "GND1")
		(10 "In4.Cu" signal "IN2")
		(12 "In5.Cu" signal "GND2")
		(14 "In6.Cu" signal "IN3")
		(16 "In7.Cu" signal "GND3")
		(18 "In8.Cu" signal "VCC")
		(20 "In9.Cu" signal "VCC1")
		(22 "In10.Cu" signal "GND4")
		(24 "In11.Cu" signal "IN4")
		(26 "In12.Cu" signal "GND5")
		(28 "In13.Cu" signal "IN5")
		(30 "In14.Cu" signal "GND6")
		(32 "In15.Cu" signal "IN6")
		(34 "In16.Cu" signal "GND7")
		(2 "B.Cu" signal "BOTTOM")
		(9 "F.Adhes" user "F.Adhesive")
		(11 "B.Adhes" user "B.Adhesive")
		(13 "F.Paste" user "Package Geometry/Pastemask Top")
		(15 "B.Paste" user "Package Geometry/Pastemask Bottom")
		(5 "F.SilkS" user "Ref Des/Silkscreen Top")
		(7 "B.SilkS" user "Ref Des/Silkscreen Bottom")
		(1 "F.Mask" user "Board Geometry/Soldermask Top")
		(3 "B.Mask" user "Board Geometry/Soldermask Bottom")
		(17 "Dwgs.User" user "User.Drawings")
		(19 "Cmts.User" user "User.Comments")
		(21 "Eco1.User" user "User.Eco1")
		(23 "Eco2.User" user "User.Eco2")
		(25 "Edge.Cuts" user "Board Geometry/Outline")
		(27 "Margin" user)
		(31 "F.CrtYd" user "Package Geometry/Place Bound Top")
		(29 "B.CrtYd" user "Package Geometry/Place Bound Bottom")
		(35 "F.Fab" user "Ref Des/Assembly Top")
		(33 "B.Fab" user "Ref Des/Assembly Bottom")
	)
	(footprint ""
		(layer "F.Cu")
		(at 180.528468 -50.974498 180)
		(property "Reference" "C1102"
			(at 0 0 180)
			(layer "F.SilkS")
			(hide yes)
			(effects
				(font
					(size 1.27 1.27)
				)
			)
		)
		(property "Value" ""
			(at 0 0 180)
			(layer "F.Fab")
			(effects
				(font
					(size 1.27 1.27)
				)
			)
		)
		(duplicate_pad_numbers_are_jumpers no)
		(fp_line
			(start 0.299974 0.150114)
			(end -0.299974 0.150114)
			(stroke
				(width 0.1)
				(type default)
			)
			(layer "F.Fab")
		)
		(fp_line
			(start 0.299974 -0.150114)
			(end 0.299974 0.150114)
			(stroke
				(width 0.1)
				(type default)
			)
			(layer "F.Fab")
		)
		(fp_line
			(start -0.299974 0.150114)
			(end -0.299974 -0.150114)
			(stroke
				(width 0.1)
				(type default)
			)
			(layer "F.Fab")
		)
		(fp_line
			(start -0.299974 -0.150114)
			(end 0.299974 -0.150114)
			(stroke
				(width 0.1)
				(type default)
			)
			(layer "F.Fab")
		)
		(pad "1" smd rect
			(at -0.2667 0 180)
			(size 0.3048 0.381)
			(layers "F.Cu" "F.Mask" "F.Paste")
			(net "P3E_PCH_M2_TX_DP<1>")
		)
		(pad "2" smd rect
			(at 0.2667 0 180)
			(size 0.3048 0.381)
			(layers "F.Cu" "F.Mask" "F.Paste")
			(net "P3E_PCH_M2_TX_C_DP<1>")
		)
		(zone
			(layer "In1.Cu")
			(hatch none 0.5)
			(connect_pads
				(clearance 0)
			)
			(min_thickness 0.25)
			(keepout
				(tracks not_allowed)
				(vias allowed)
				(pads allowed)
				(copperpour not_allowed)
				(footprints allowed)
			)
			(placement
				(enabled no)
				(sheetname "")
			)
			(fill
				(thermal_gap 0.5)
				(thermal_bridge_width 0.5)
				(island_removal_mode 0)
			)
			(polygon
				(pts
					(arc
						(start 180.388768 -51.215798)
						(mid 180.44265 -51.19348)
						(end 180.464968 -51.139598)
					)
					(arc
						(start 180.464968 -50.809398)
						(mid 180.44265 -50.755516)
						(end 180.388768 -50.733198)
					)
					(arc
						(start 180.134768 -50.733198)
						(mid 180.080886 -50.755516)
						(end 180.058568 -50.809398)
					)
					(arc
						(start 180.058568 -51.139598)
						(mid 180.080886 -51.19348)
						(end 180.134768 -51.215798)
					)
				)
			)
		)
		(zone
			(layer "In1.Cu")
			(hatch none 0.5)
			(connect_pads
				(clearance 0)
			)
			(min_thickness 0.25)
			(keepout
				(tracks not_allowed)
				(vias allowed)
				(pads allowed)
				(copperpour not_allowed)
				(footprints allowed)
			)
			(placement
				(enabled no)
				(sheetname "")
			)
			(fill
				(thermal_gap 0.5)
				(thermal_bridge_width 0.5)
				(island_removal_mode 0)
			)
			(polygon
				(pts
					(arc
						(start 180.922168 -51.215798)
						(mid 180.97605 -51.19348)
						(end 180.998368 -51.139598)
					)
					(arc
						(start 180.998368 -50.809398)
						(mid 180.97605 -50.755516)
						(end 180.922168 -50.733198)
					)
					(arc
						(start 180.668168 -50.733198)
						(mid 180.614286 -50.755516)
						(end 180.591968 -50.809398)
					)
					(arc
						(start 180.591968 -51.139598)
						(mid 180.614286 -51.19348)
						(end 180.668168 -51.215798)
					)
				)
			)
		)
	)
	(footprint ""
		(layer "F.Cu")
		(at 438.28208 -16.220948 -90)
		(property "Reference" "R416"
			(at 0 0 270)
			(layer "F.SilkS")
			(hide yes)
			(effects
				(font
					(size 1.27 1.27)
				)
			)
		)
		(property "Value" ""
			(at 0 0 270)
			(layer "F.Fab")
			(effects
				(font
					(size 1.27 1.27)
				)
			)
		)
		(duplicate_pad_numbers_are_jumpers no)
		(fp_line
			(start -0.7874 0.4064)
			(end -0.7874 -0.4064)
			(stroke
				(width 0.1524)
				(type default)
			)
			(layer "F.SilkS")
		)
		(fp_line
			(start 0.7874 0.4064)
			(end -0.7874 0.4064)
			(stroke
				(width 0.1524)
				(type default)
			)
			(layer "F.SilkS")
		)
		(fp_line
			(start -0.7874 -0.4064)
			(end 0.7874 -0.4064)
			(stroke
				(width 0.1524)
				(type default)
			)
			(layer "F.SilkS")
		)
		(fp_line
			(start 0.7874 -0.4064)
			(end 0.7874 0.4064)
			(stroke
				(width 0.1524)
				(type default)
			)
			(layer "F.SilkS")
		)
		(fp_line
			(start -0.67945 0.3048)
			(end -0.67945 -0.305054)
			(stroke
				(width 0.1)
				(type default)
			)
			(layer "F.Fab")
		)
		(fp_line
			(start -0.12065 0.3048)
			(end -0.67945 0.3048)
			(stroke
				(width 0.1)
				(type default)
			)
			(layer "F.Fab")
		)
		(fp_line
			(start 0.120396 0.3048)
			(end 0.120396 0.2794)
			(stroke
				(width 0.1)
				(type default)
			)
			(layer "F.Fab")
		)
		(fp_line
			(start 0.67945 0.3048)
			(end 0.120396 0.3048)
			(stroke
				(width 0.1)
				(type default)
			)
			(layer "F.Fab")
		)
		(fp_line
			(start -0.12065 0.2794)
			(end -0.12065 0.3048)
			(stroke
				(width 0.1)
				(type default)
			)
			(layer "F.Fab")
		)
		(fp_line
			(start 0.120396 0.2794)
			(end -0.12065 0.2794)
			(stroke
				(width 0.1)
				(type default)
			)
			(layer "F.Fab")
		)
		(fp_line
			(start -0.12065 -0.2794)
			(end 0.12065 -0.2794)
			(stroke
				(width 0.1)
				(type default)
			)
			(layer "F.Fab")
		)
		(fp_line
			(start 0.12065 -0.2794)
			(end 0.12065 -0.3048)
			(stroke
				(width 0.1)
				(type default)
			)
			(layer "F.Fab")
		)
		(fp_line
			(start 0.12065 -0.3048)
			(end 0.67945 -0.3048)
			(stroke
				(width 0.1)
				(type default)
			)
			(layer "F.Fab")
		)
		(fp_line
			(start 0.67945 -0.3048)
			(end 0.67945 0.3048)
			(stroke
				(width 0.1)
				(type default)
			)
			(layer "F.Fab")
		)
		(fp_line
			(start -0.67945 -0.305054)
			(end -0.12065 -0.305054)
			(stroke
				(width 0.1)
				(type default)
			)
			(layer "F.Fab")
		)
		(fp_line
			(start -0.12065 -0.305054)
			(end -0.12065 -0.2794)
			(stroke
				(width 0.1)
				(type default)
			)
			(layer "F.Fab")
		)
		(pad "1" smd circle
			(at -0.40005 0 270)
			(size 0 0)
			(layers "F.Cu" "F.Mask" "F.Paste")
			(net "OCP_SFF_ISO_BIF0_EN")
		)
		(pad "2" smd circle
			(at 0.40005 0 270)
			(size 0 0)
			(layers "F.Cu" "F.Mask" "F.Paste")
			(net "OCP_SFF_BIF0_R_N")
		)
	)
	(footprint ""
		(layer "F.Cu")
		(at 145.940018 -251.76988)
		(property "Reference" "H26"
			(at 2.44602 -1.372108 0)
			(unlocked yes)
			(layer "F.SilkS")
			(effects
				(font
					(size 0.7874 0.5842)
					(thickness 0.1524)
				)
				(justify left)
			)
		)
		(property "Value" ""
			(at 0 0 0)
			(layer "F.Fab")
			(effects
				(font
					(size 1.27 1.27)
				)
			)
		)
		(duplicate_pad_numbers_are_jumpers no)
		(fp_circle
			(center 0 0)
			(end 2.5273 0)
			(stroke
				(width 0.1524)
				(type default)
			)
			(fill no)
			(layer "F.SilkS")
		)
		(fp_circle
			(center 0 0)
			(end 2.5273 0)
			(stroke
				(width 0.1524)
				(type default)
			)
			(fill no)
			(layer "B.SilkS")
		)
		(fp_circle
			(center 0 0)
			(end 2.5273 0)
			(stroke
				(width 0.1)
				(type default)
			)
			(fill no)
			(layer "B.Fab")
		)
		(fp_circle
			(center 0 0)
			(end 2.5273 0)
			(stroke
				(width 0.1)
				(type default)
			)
			(fill no)
			(layer "F.Fab")
		)
		(pad "" np_thru_hole circle
			(at 0 0)
			(size 3.429 3.429)
			(drill 3.429)
			(layers "*.Cu" "*.Mask")
			(clearance 0.381)
			(thermal_gap 0.381)
		)
	)
)
